# SCM (Grand Teton) — schematic netlist excerpt (pin names and nets, part order shuffled) for the footprints in the layout excerpt that follows; sources: Cadence DE-HDL packaged netlist, KiCad conversion of 12092022_DA0F0TMDCD0_F0T_Management_Board_D_brd_V3_OCP.brd

R901  Q_RES  0 5% CHIP  pkg 0402LF  page 31 : A = UART_6_BMC_RXD ; B = UART_6_BMC_RXD_R

U15  74LVC1G08GW  IC  pkg SM  page 15
  B  = SYS_BMC_PWRBTN_R_N
  A  = PWR_BTN_BMC_N
  GND  = GND
  Y  = SYS_PWRBTN_N
  VCC  = P3V3_AUX

(kicad_pcb
	(version 20260206)
	(generator "pcbnew")
	(generator_version "10.0")
	(general
		(thickness 1.6)
		(legacy_teardrops no)
	)
	(paper "A4")
	(title_block
		(title "12092022_DA0F0TMDCD0_F0T_Management_Board_D_brd_V3_OCP.brd")
		(comment 1 "Grand Teton / footprints 559-560 of 1440")
	)
	(layers
		(0 "F.Cu" signal "TOP")
		(4 "In1.Cu" signal "GND")
		(6 "In2.Cu" signal "IN1")
		(8 "In3.Cu" signal "GND1")
		(10 "In4.Cu" signal "IN2")
		(12 "In5.Cu" signal "VCC")
		(14 "In6.Cu" signal "VCC1")
		(16 "In7.Cu" signal "IN3")
		(18 "In8.Cu" signal "GND2")
		(20 "In9.Cu" signal "IN4")
		(22 "In10.Cu" signal "GND3")
		(2 "B.Cu" signal "BOTTOM")
		(9 "F.Adhes" user "F.Adhesive")
		(11 "B.Adhes" user "B.Adhesive")
		(13 "F.Paste" user "Package Geometry/Pastemask Top")
		(15 "B.Paste" user "Package Geometry/Pastemask Bottom")
		(5 "F.SilkS" user "Ref Des/Silkscreen Top")
		(7 "B.SilkS" user "Ref Des/Silkscreen Bottom")
		(1 "F.Mask" user "Board Geometry/Soldermask Top")
		(3 "B.Mask" user "Board Geometry/Soldermask Bottom")
		(17 "Dwgs.User" user "User.Drawings")
		(19 "Cmts.User" user "User.Comments")
		(21 "Eco1.User" user "User.Eco1")
		(23 "Eco2.User" user "User.Eco2")
		(25 "Edge.Cuts" user "Board Geometry/Outline")
		(27 "Margin" user)
		(31 "F.CrtYd" user "Package Geometry/Place Bound Top")
		(29 "B.CrtYd" user "Package Geometry/Place Bound Bottom")
		(35 "F.Fab" user "Ref Des/Assembly Top")
		(33 "B.Fab" user "Ref Des/Assembly Bottom")
	)
	(footprint ""
		(layer "F.Cu")
		(at 40.132 -70.485 90)
		(property "Reference" "U15"
			(at -1.1684 -1.70053 90)
			(unlocked yes)
			(layer "F.SilkS")
			(effects
				(font
					(size 0.7874 0.5842)
					(thickness 0.1524)
				)
			)
		)
		(property "Value" ""
			(at 0 0 90)
			(layer "F.Fab")
			(effects
				(font
					(size 1.27 1.27)
				)
			)
		)
		(duplicate_pad_numbers_are_jumpers no)
		(fp_line
			(start 1.7018 -1.1176)
			(end 0.254 -1.1176)
			(stroke
				(width 0.1524)
				(type default)
			)
			(layer "F.SilkS")
		)
		(fp_line
			(start 1.7018 -1.1176)
			(end 1.7018 1.1176)
			(stroke
				(width 0.1524)
				(type default)
			)
			(layer "F.SilkS")
		)
		(fp_line
			(start 0.254 -1.1176)
			(end 0 -0.7112)
			(stroke
				(width 0.1524)
				(type default)
			)
			(layer "F.SilkS")
		)
		(fp_line
			(start -0.254 -1.1176)
			(end -1.7018 -1.1176)
			(stroke
				(width 0.1524)
				(type default)
			)
			(layer "F.SilkS")
		)
		(fp_line
			(start 0 -0.7112)
			(end -0.254 -1.1176)
			(stroke
				(width 0.1524)
				(type default)
			)
			(layer "F.SilkS")
		)
		(fp_line
			(start 1.7018 1.1176)
			(end -1.7018 1.1176)
			(stroke
				(width 0.1524)
				(type default)
			)
			(layer "F.SilkS")
		)
		(fp_line
			(start -1.7018 1.1176)
			(end -1.7018 -1.1176)
			(stroke
				(width 0.1524)
				(type default)
			)
			(layer "F.SilkS")
		)
		(fp_poly
			(pts
				(xy -1.8161 -0.675386) (xy -2.4003 -0.446786) (xy -2.4003 -0.878586)
			)
			(stroke
				(width 0)
				(type default)
			)
			(fill yes)
			(layer "F.SilkS")
		)
		(fp_line
			(start 1.5494 -1.1176)
			(end 0.254 -1.1176)
			(stroke
				(width 0.1)
				(type default)
			)
			(layer "F.Fab")
		)
		(fp_line
			(start 1.5494 -1.1176)
			(end 1.5494 1.1176)
			(stroke
				(width 0.1)
				(type default)
			)
			(layer "F.Fab")
		)
		(fp_line
			(start 0.254 -1.1176)
			(end -0.254 -1.1176)
			(stroke
				(width 0.1)
				(type default)
			)
			(layer "F.Fab")
		)
		(fp_line
			(start -0.254 -1.1176)
			(end -1.5494 -1.1176)
			(stroke
				(width 0.1)
				(type default)
			)
			(layer "F.Fab")
		)
		(fp_line
			(start 1.5494 1.1176)
			(end -1.5494 1.1176)
			(stroke
				(width 0.1)
				(type default)
			)
			(layer "F.Fab")
		)
		(fp_line
			(start -1.5494 1.1176)
			(end -1.5494 -1.1176)
			(stroke
				(width 0.1)
				(type default)
			)
			(layer "F.Fab")
		)
		(fp_poly
			(pts
				(xy -1.8161 -0.675386) (xy -2.4003 -0.446786) (xy -2.4003 -0.878586)
			)
			(stroke
				(width 0)
				(type default)
			)
			(fill yes)
			(layer "F.Fab")
		)
		(pad "1" smd rect
			(at -0.962406 -0.649986)
			(size 0.3302 1.1684)
			(layers "F.Cu" "F.Mask" "F.Paste")
			(net "SYS_BMC_PWRBTN_R_N")
		)
		(pad "2" smd rect
			(at -0.962406 0)
			(size 0.3302 1.1684)
			(layers "F.Cu" "F.Mask" "F.Paste")
			(net "PWR_BTN_BMC_N")
		)
		(pad "3" smd rect
			(at -0.962406 0.649986)
			(size 0.3302 1.1684)
			(layers "F.Cu" "F.Mask" "F.Paste")
			(net "GND")
		)
		(pad "4" smd rect
			(at 0.962406 0.649986)
			(size 0.3302 1.1684)
			(layers "F.Cu" "F.Mask" "F.Paste")
			(net "SYS_PWRBTN_N")
		)
		(pad "5" smd rect
			(at 0.962406 -0.649986)
			(size 0.3302 1.1684)
			(layers "F.Cu" "F.Mask" "F.Paste")
			(net "P3V3_AUX")
		)
	)
	(footprint ""
		(layer "F.Cu")
		(at 19.685 -56.1848 90)
		(property "Reference" "R901"
			(at 0 0 90)
			(layer "F.SilkS")
			(hide yes)
			(effects
				(font
					(size 1.27 1.27)
				)
			)
		)
		(property "Value" ""
			(at 0 0 90)
			(layer "F.Fab")
			(effects
				(font
					(size 1.27 1.27)
				)
			)
		)
		(duplicate_pad_numbers_are_jumpers no)
		(fp_line
			(start 0.7874 -0.4064)
			(end 0.7874 0.4064)
			(stroke
				(width 0.1524)
				(type default)
			)
			(layer "F.SilkS")
		)
		(fp_line
			(start -0.7874 -0.4064)
			(end 0.7874 -0.4064)
			(stroke
				(width 0.1524)
				(type default)
			)
			(layer "F.SilkS")
		)
		(fp_line
			(start 0.7874 0.4064)
			(end -0.7874 0.4064)
			(stroke
				(width 0.1524)
				(type default)
			)
			(layer "F.SilkS")
		)
		(fp_line
			(start -0.7874 0.4064)
			(end -0.7874 -0.4064)
			(stroke
				(width 0.1524)
				(type default)
			)
			(layer "F.SilkS")
		)
		(fp_line
			(start -0.12065 -0.305054)
			(end -0.12065 -0.2794)
			(stroke
				(width 0.1)
				(type default)
			)
			(layer "F.Fab")
		)
		(fp_line
			(start -0.67945 -0.305054)
			(end -0.12065 -0.305054)
			(stroke
				(width 0.1)
				(type default)
			)
			(layer "F.Fab")
		)
		(fp_line
			(start 0.67945 -0.3048)
			(end 0.67945 0.3048)
			(stroke
				(width 0.1)
				(type default)
			)
			(layer "F.Fab")
		)
		(fp_line
			(start 0.12065 -0.3048)
			(end 0.67945 -0.3048)
			(stroke
				(width 0.1)
				(type default)
			)
			(layer "F.Fab")
		)
		(fp_line
			(start 0.12065 -0.2794)
			(end 0.12065 -0.3048)
			(stroke
				(width 0.1)
				(type default)
			)
			(layer "F.Fab")
		)
		(fp_line
			(start -0.12065 -0.2794)
			(end 0.12065 -0.2794)
			(stroke
				(width 0.1)
				(type default)
			)
			(layer "F.Fab")
		)
		(fp_line
			(start 0.120396 0.2794)
			(end -0.12065 0.2794)
			(stroke
				(width 0.1)
				(type default)
			)
			(layer "F.Fab")
		)
		(fp_line
			(start -0.12065 0.2794)
			(end -0.12065 0.3048)
			(stroke
				(width 0.1)
				(type default)
			)
			(layer "F.Fab")
		)
		(fp_line
			(start 0.67945 0.3048)
			(end 0.120396 0.3048)
			(stroke
				(width 0.1)
				(type default)
			)
			(layer "F.Fab")
		)
		(fp_line
			(start 0.120396 0.3048)
			(end 0.120396 0.2794)
			(stroke
				(width 0.1)
				(type default)
			)
			(layer "F.Fab")
		)
		(fp_line
			(start -0.12065 0.3048)
			(end -0.67945 0.3048)
			(stroke
				(width 0.1)
				(type default)
			)
			(layer "F.Fab")
		)
		(fp_line
			(start -0.67945 0.3048)
			(end -0.67945 -0.305054)
			(stroke
				(width 0.1)
				(type default)
			)
			(layer "F.Fab")
		)
		(pad "1" smd circle
			(at -0.40005 0 90)
			(size 0 0)
			(layers "F.Cu" "F.Mask" "F.Paste")
			(net "UART_6_BMC_RXD")
		)
		(pad "2" smd circle
			(at 0.40005 0 90)
			(size 0 0)
			(layers "F.Cu" "F.Mask" "F.Paste")
			(net "UART_6_BMC_RXD_R")
		)
	)
)
